FILE_TYPE = MULTI_PHYS_TABLE;

PART 'SN74LVC1G14DCKR'

{========================================================================================}
:PACK_TYPE | MATERIAL | VALUE             | PART_NUMBER      = STANDARD         | LIFECYCLE        | PART_NUMBER   | JEDEC_TYPE | CLASS | DESCRIPTION                    | HEIGHT    | COMPONENT_TYPE | LEAD_LENGTH | DFM_EXCLUSION | LPID | DAY        ;
{========================================================================================}
 'SMLF'    | 'IC'     | 'SN74LVC1G14DCKR' | 'AL001G14017'(!) = ''               | ''               | 'AL001G14017' |'SC70-5'| 'IC'  | 'IC(5P) SN74LVC1G14DCKR(SC70)' | '0.044IN' | 'SMALLSMT'     | ''          | ''            | ''   | '20100623'
 'SMLF'    | 'EMPTY'  | 'SN74LVC1G14DCKR' | 'AL001G14017'(!) = ''               | ''               | 'AL001G14017' |'SC70-5'| 'IO'  | 'IC(5P) SN74LVC1G14DCKR(SC70)' | '0.044IN' | 'SMALLSMT'     | ''          | ''            | ''   | '20100623'

END_PART

END.

